# S9S_MB_2U (Grand Teton) — schematic netlist excerpt (pin names and nets, part order shuffled) for the footprints in the layout excerpt that follows; sources: Cadence DE-HDL packaged netlist, KiCad conversion of 03242023_DA0F0TMBIJ0_F0T_Motherboard_J_brd_V01_OCP.brd

R3037  Q_RES  1K 1% EMPTY  pkg 0402LF  page 158 : A = P3V3_AUX ; B = PD_SMB_OCP1_HP_ADD1
R4084  Q_RES  0 5% EMPTY  pkg 0402LF  page 183 : A = E1S_0_PRSNT_N ; B = E1S_0_CLKREQ_N
C1555  Q_CAP_DIFFBUS  DIFF BUS_0.22UF 6.3V 20% X6S  pkg C0201  page 175 : \1\ = P5E_CPU0_PE4_TX_C_DP<12> ; \2\ = P5E_CPU0_PE4_TX_DP<12>

(kicad_pcb
	(version 20260206)
	(generator "pcbnew")
	(generator_version "10.0")
	(general
		(thickness 1.6)
		(legacy_teardrops no)
	)
	(paper "A4")
	(title_block
		(title "03242023_DA0F0TMBIJ0_F0T_Motherboard_J_brd_V01_OCP.brd")
		(comment 1 "Grand Teton / footprints 877-879 of 6105")
	)
	(layers
		(0 "F.Cu" signal "TOP")
		(4 "In1.Cu" signal "GND")
		(6 "In2.Cu" signal "IN1")
		(8 "In3.Cu" signal "GND1")
		(10 "In4.Cu" signal "IN2")
		(12 "In5.Cu" signal "GND2")
		(14 "In6.Cu" signal "IN3")
		(16 "In7.Cu" signal "GND3")
		(18 "In8.Cu" signal "VCC")
		(20 "In9.Cu" signal "VCC1")
		(22 "In10.Cu" signal "GND4")
		(24 "In11.Cu" signal "IN4")
		(26 "In12.Cu" signal "GND5")
		(28 "In13.Cu" signal "IN5")
		(30 "In14.Cu" signal "GND6")
		(32 "In15.Cu" signal "IN6")
		(34 "In16.Cu" signal "GND7")
		(2 "B.Cu" signal "BOTTOM")
		(9 "F.Adhes" user "F.Adhesive")
		(11 "B.Adhes" user "B.Adhesive")
		(13 "F.Paste" user "Package Geometry/Pastemask Top")
		(15 "B.Paste" user "Package Geometry/Pastemask Bottom")
		(5 "F.SilkS" user "Ref Des/Silkscreen Top")
		(7 "B.SilkS" user "Ref Des/Silkscreen Bottom")
		(1 "F.Mask" user "Board Geometry/Soldermask Top")
		(3 "B.Mask" user "Board Geometry/Soldermask Bottom")
		(17 "Dwgs.User" user "User.Drawings")
		(19 "Cmts.User" user "User.Comments")
		(21 "Eco1.User" user "User.Eco1")
		(23 "Eco2.User" user "User.Eco2")
		(25 "Edge.Cuts" user "Board Geometry/Outline")
		(27 "Margin" user)
		(31 "F.CrtYd" user "Package Geometry/Place Bound Top")
		(29 "B.CrtYd" user "Package Geometry/Place Bound Bottom")
		(35 "F.Fab" user "Ref Des/Assembly Top")
		(33 "B.Fab" user "Ref Des/Assembly Bottom")
	)
	(footprint ""
		(layer "F.Cu")
		(at 224.2312 -51.0921 180)
		(property "Reference" "R4084"
			(at 0 0 180)
			(layer "F.SilkS")
			(hide yes)
			(effects
				(font
					(size 1.27 1.27)
				)
			)
		)
		(property "Value" ""
			(at 0 0 180)
			(layer "F.Fab")
			(effects
				(font
					(size 1.27 1.27)
				)
			)
		)
		(duplicate_pad_numbers_are_jumpers no)
		(fp_line
			(start 0.7874 0.4064)
			(end -0.7874 0.4064)
			(stroke
				(width 0.1524)
				(type default)
			)
			(layer "F.SilkS")
		)
		(fp_line
			(start 0.7874 -0.4064)
			(end 0.7874 0.4064)
			(stroke
				(width 0.1524)
				(type default)
			)
			(layer "F.SilkS")
		)
		(fp_line
			(start -0.7874 0.4064)
			(end -0.7874 -0.4064)
			(stroke
				(width 0.1524)
				(type default)
			)
			(layer "F.SilkS")
		)
		(fp_line
			(start -0.7874 -0.4064)
			(end 0.7874 -0.4064)
			(stroke
				(width 0.1524)
				(type default)
			)
			(layer "F.SilkS")
		)
		(fp_line
			(start 0.67945 0.3048)
			(end 0.120396 0.3048)
			(stroke
				(width 0.1)
				(type default)
			)
			(layer "F.Fab")
		)
		(fp_line
			(start 0.67945 -0.3048)
			(end 0.67945 0.3048)
			(stroke
				(width 0.1)
				(type default)
			)
			(layer "F.Fab")
		)
		(fp_line
			(start 0.12065 -0.2794)
			(end 0.12065 -0.3048)
			(stroke
				(width 0.1)
				(type default)
			)
			(layer "F.Fab")
		)
		(fp_line
			(start 0.12065 -0.3048)
			(end 0.67945 -0.3048)
			(stroke
				(width 0.1)
				(type default)
			)
			(layer "F.Fab")
		)
		(fp_line
			(start 0.120396 0.3048)
			(end 0.120396 0.2794)
			(stroke
				(width 0.1)
				(type default)
			)
			(layer "F.Fab")
		)
		(fp_line
			(start 0.120396 0.2794)
			(end -0.12065 0.2794)
			(stroke
				(width 0.1)
				(type default)
			)
			(layer "F.Fab")
		)
		(fp_line
			(start -0.12065 0.3048)
			(end -0.67945 0.3048)
			(stroke
				(width 0.1)
				(type default)
			)
			(layer "F.Fab")
		)
		(fp_line
			(start -0.12065 0.2794)
			(end -0.12065 0.3048)
			(stroke
				(width 0.1)
				(type default)
			)
			(layer "F.Fab")
		)
		(fp_line
			(start -0.12065 -0.2794)
			(end 0.12065 -0.2794)
			(stroke
				(width 0.1)
				(type default)
			)
			(layer "F.Fab")
		)
		(fp_line
			(start -0.12065 -0.305054)
			(end -0.12065 -0.2794)
			(stroke
				(width 0.1)
				(type default)
			)
			(layer "F.Fab")
		)
		(fp_line
			(start -0.67945 0.3048)
			(end -0.67945 -0.305054)
			(stroke
				(width 0.1)
				(type default)
			)
			(layer "F.Fab")
		)
		(fp_line
			(start -0.67945 -0.305054)
			(end -0.12065 -0.305054)
			(stroke
				(width 0.1)
				(type default)
			)
			(layer "F.Fab")
		)
		(pad "1" smd circle
			(at -0.40005 0 180)
			(size 0 0)
			(layers "F.Cu" "F.Mask" "F.Paste")
			(net "E1S_0_PRSNT_N")
		)
		(pad "2" smd circle
			(at 0.40005 0 180)
			(size 0 0)
			(layers "F.Cu" "F.Mask" "F.Paste")
			(net "E1S_0_CLKREQ_N")
		)
	)
	(footprint ""
		(layer "F.Cu")
		(at 341.627968 -402.371052 -90)
		(property "Reference" "C1555"
			(at 0 0 270)
			(layer "F.SilkS")
			(hide yes)
			(effects
				(font
					(size 1.27 1.27)
				)
			)
		)
		(property "Value" ""
			(at 0 0 270)
			(layer "F.Fab")
			(effects
				(font
					(size 1.27 1.27)
				)
			)
		)
		(duplicate_pad_numbers_are_jumpers no)
		(fp_line
			(start -0.299974 0.150114)
			(end -0.299974 -0.150114)
			(stroke
				(width 0.1)
				(type default)
			)
			(layer "F.Fab")
		)
		(fp_line
			(start 0.299974 0.150114)
			(end -0.299974 0.150114)
			(stroke
				(width 0.1)
				(type default)
			)
			(layer "F.Fab")
		)
		(fp_line
			(start -0.299974 -0.150114)
			(end 0.299974 -0.150114)
			(stroke
				(width 0.1)
				(type default)
			)
			(layer "F.Fab")
		)
		(fp_line
			(start 0.299974 -0.150114)
			(end 0.299974 0.150114)
			(stroke
				(width 0.1)
				(type default)
			)
			(layer "F.Fab")
		)
		(pad "1" smd rect
			(at -0.2667 0 270)
			(size 0.3048 0.381)
			(layers "F.Cu" "F.Mask" "F.Paste")
			(net "P5E_CPU0_PE4_TX_C_DP<12>")
		)
		(pad "2" smd rect
			(at 0.2667 0 270)
			(size 0.3048 0.381)
			(layers "F.Cu" "F.Mask" "F.Paste")
			(net "P5E_CPU0_PE4_TX_DP<12>")
		)
	)
	(footprint ""
		(layer "F.Cu")
		(at 447.510154 -118.336822)
		(property "Reference" "R3037"
			(at 0 0 0)
			(layer "F.SilkS")
			(hide yes)
			(effects
				(font
					(size 1.27 1.27)
				)
			)
		)
		(property "Value" ""
			(at 0 0 0)
			(layer "F.Fab")
			(effects
				(font
					(size 1.27 1.27)
				)
			)
		)
		(duplicate_pad_numbers_are_jumpers no)
		(fp_line
			(start -0.7874 -0.4064)
			(end 0.7874 -0.4064)
			(stroke
				(width 0.1524)
				(type default)
			)
			(layer "F.SilkS")
		)
		(fp_line
			(start -0.7874 0.4064)
			(end -0.7874 -0.4064)
			(stroke
				(width 0.1524)
				(type default)
			)
			(layer "F.SilkS")
		)
		(fp_line
			(start 0.7874 -0.4064)
			(end 0.7874 0.4064)
			(stroke
				(width 0.1524)
				(type default)
			)
			(layer "F.SilkS")
		)
		(fp_line
			(start 0.7874 0.4064)
			(end -0.7874 0.4064)
			(stroke
				(width 0.1524)
				(type default)
			)
			(layer "F.SilkS")
		)
		(fp_line
			(start -0.67945 -0.305054)
			(end -0.12065 -0.305054)
			(stroke
				(width 0.1)
				(type default)
			)
			(layer "F.Fab")
		)
		(fp_line
			(start -0.67945 0.3048)
			(end -0.67945 -0.305054)
			(stroke
				(width 0.1)
				(type default)
			)
			(layer "F.Fab")
		)
		(fp_line
			(start -0.12065 -0.305054)
			(end -0.12065 -0.2794)
			(stroke
				(width 0.1)
				(type default)
			)
			(layer "F.Fab")
		)
		(fp_line
			(start -0.12065 -0.2794)
			(end 0.12065 -0.2794)
			(stroke
				(width 0.1)
				(type default)
			)
			(layer "F.Fab")
		)
		(fp_line
			(start -0.12065 0.2794)
			(end -0.12065 0.3048)
			(stroke
				(width 0.1)
				(type default)
			)
			(layer "F.Fab")
		)
		(fp_line
			(start -0.12065 0.3048)
			(end -0.67945 0.3048)
			(stroke
				(width 0.1)
				(type default)
			)
			(layer "F.Fab")
		)
		(fp_line
			(start 0.120396 0.2794)
			(end -0.12065 0.2794)
			(stroke
				(width 0.1)
				(type default)
			)
			(layer "F.Fab")
		)
		(fp_line
			(start 0.120396 0.3048)
			(end 0.120396 0.2794)
			(stroke
				(width 0.1)
				(type default)
			)
			(layer "F.Fab")
		)
		(fp_line
			(start 0.12065 -0.3048)
			(end 0.67945 -0.3048)
			(stroke
				(width 0.1)
				(type default)
			)
			(layer "F.Fab")
		)
		(fp_line
			(start 0.12065 -0.2794)
			(end 0.12065 -0.3048)
			(stroke
				(width 0.1)
				(type default)
			)
			(layer "F.Fab")
		)
		(fp_line
			(start 0.67945 -0.3048)
			(end 0.67945 0.3048)
			(stroke
				(width 0.1)
				(type default)
			)
			(layer "F.Fab")
		)
		(fp_line
			(start 0.67945 0.3048)
			(end 0.120396 0.3048)
			(stroke
				(width 0.1)
				(type default)
			)
			(layer "F.Fab")
		)
		(pad "1" smd circle
			(at -0.40005 0)
			(size 0 0)
			(layers "F.Cu" "F.Mask" "F.Paste")
			(net "P3V3_AUX")
		)
		(pad "2" smd circle
			(at 0.40005 0)
			(size 0 0)
			(layers "F.Cu" "F.Mask" "F.Paste")
			(net "PD_SMB_OCP1_HP_ADD1")
		)
	)
)
